(kicad_pcb
	(version 20260206)
	(generator "pcbnew")
	(generator_version "10.0")
	(general
		(thickness 1.6)
		(legacy_teardrops no)
	)
	(paper "A4")
	(title_block
		(title "Bryce Canyon_R.DPB_16317-1_OCP.brd")
		(comment 1 "Bryce Canyon / footprints 1247-1254 of 2099")
	)
	(layers
		(0 "F.Cu" signal "TOP")
		(4 "In1.Cu" signal "L2GND")
		(6 "In2.Cu" signal "L3")
		(8 "In3.Cu" signal "L4VCC")
		(10 "In4.Cu" signal "L5VCC")
		(12 "In5.Cu" signal "L6")
		(14 "In6.Cu" signal "L7GND")
		(2 "B.Cu" signal "BOTTOM")
		(9 "F.Adhes" user "F.Adhesive")
		(11 "B.Adhes" user "B.Adhesive")
		(13 "F.Paste" user "Package Geometry/Pastemask Top")
		(15 "B.Paste" user "Package Geometry/Pastemask Bottom")
		(5 "F.SilkS" user "Ref Des/Silkscreen Top")
		(7 "B.SilkS" user "Ref Des/Silkscreen Bottom")
		(1 "F.Mask" user "Board Geometry/Soldermask Top")
		(3 "B.Mask" user "Board Geometry/Soldermask Bottom")
		(17 "Dwgs.User" user "User.Drawings")
		(19 "Cmts.User" user "User.Comments")
		(21 "Eco1.User" user "User.Eco1")
		(23 "Eco2.User" user "User.Eco2")
		(25 "Edge.Cuts" user "Board Geometry/Outline")
		(27 "Margin" user)
		(31 "F.CrtYd" user "Package Geometry/Place Bound Top")
		(29 "B.CrtYd" user "Package Geometry/Place Bound Bottom")
		(35 "F.Fab" user "Ref Des/Assembly Top")
		(33 "B.Fab" user "Ref Des/Assembly Bottom")
	)
	(footprint ""
		(layer "F.Cu")
		(at 161.163 -371.983 90)
		(property "Reference" "R935"
			(at 0 0 90)
			(layer "F.SilkS")
			(hide yes)
			(effects
				(font
					(size 1.27 1.27)
				)
			)
		)
		(property "Value" "0R2J-2-GP"
			(at 0.064008 -3.993896 90)
			(unlocked yes)
			(layer "F.Fab")
			(hide yes)
			(effects
				(font
					(size 1.016 1.016)
					(thickness 0.1524)
				)
			)
		)
		(property "Device Type" "R402H16"
			(at 0.064008 -5.517896 90)
			(unlocked yes)
			(layer "F.Fab")
			(hide yes)
			(effects
				(font
					(size 1.016 1.016)
					(thickness 0.1524)
				)
			)
		)
		(duplicate_pad_numbers_are_jumpers no)
		(fp_line
			(start 0.508 -0.9398)
			(end -0.508 -0.9398)
			(stroke
				(width 0.1524)
				(type default)
			)
			(layer "F.SilkS")
		)
		(fp_line
			(start -0.508 -0.9398)
			(end -0.508 0.9398)
			(stroke
				(width 0.1524)
				(type default)
			)
			(layer "F.SilkS")
		)
		(fp_rect
			(start -0.508 0.9398)
			(end 0.508 -0.9398)
			(stroke
				(width 0)
				(type default)
			)
			(fill no)
			(layer "F.CrtYd")
		)
		(fp_rect
			(start -0.508 0.9398)
			(end 0.508 -0.9398)
			(stroke
				(width 0)
				(type default)
			)
			(fill no)
			(layer "F.Fab")
		)
		(pad "1" smd custom
			(at 0 -0.4445 90)
			(size 0.1397 0.1397)
			(layers "F.Cu" "F.Mask" "F.Paste")
			(net "FAN_1_PWM")
			(options
				(clearance outline)
				(anchor circle)
			)
			(primitives
				(gr_poly
					(pts
						(arc
							(start -0.1778 -0.2794)
							(mid -0.249642 -0.249642)
							(end -0.2794 -0.1778)
						)
						(arc
							(start -0.2794 0.1778)
							(mid -0.249642 0.249642)
							(end -0.1778 0.2794)
						)
						(arc
							(start 0.1778 0.2794)
							(mid 0.249642 0.249642)
							(end 0.2794 0.1778)
						)
						(arc
							(start 0.2794 -0.1778)
							(mid 0.249642 -0.249642)
							(end 0.1778 -0.2794)
						)
					)
					(width 0)
					(fill yes)
				)
			)
		)
		(pad "2" smd custom
			(at 0 0.4445 90)
			(size 0.1397 0.1397)
			(layers "F.Cu" "F.Mask" "F.Paste")
			(net "PWM_OUT_FAN1")
			(options
				(clearance outline)
				(anchor circle)
			)
			(primitives
				(gr_poly
					(pts
						(arc
							(start -0.1778 -0.2794)
							(mid -0.249642 -0.249642)
							(end -0.2794 -0.1778)
						)
						(arc
							(start -0.2794 0.1778)
							(mid -0.249642 0.249642)
							(end -0.1778 0.2794)
						)
						(arc
							(start 0.1778 0.2794)
							(mid 0.249642 0.249642)
							(end 0.2794 0.1778)
						)
						(arc
							(start 0.2794 -0.1778)
							(mid 0.249642 -0.249642)
							(end 0.1778 -0.2794)
						)
					)
					(width 0)
					(fill yes)
				)
			)
		)
	)
	(footprint ""
		(layer "F.Cu")
		(at 46.355 -140.462 90)
		(property "Reference" "C208"
			(at 0 0 90)
			(layer "F.SilkS")
			(hide yes)
			(effects
				(font
					(size 1.27 1.27)
				)
			)
		)
		(property "Value" "SCD033U25V2KX-GP"
			(at 1.1811 -2.7051 90)
			(unlocked yes)
			(layer "F.Fab")
			(hide yes)
			(effects
				(font
					(size 1.016 1.016)
					(thickness 0.1524)
				)
			)
		)
		(property "Device Type" "C402H22"
			(at 1.1811 -4.2291 90)
			(unlocked yes)
			(layer "F.Fab")
			(hide yes)
			(effects
				(font
					(size 1.016 1.016)
					(thickness 0.1524)
				)
			)
		)
		(duplicate_pad_numbers_are_jumpers no)
		(fp_rect
			(start -0.4318 0.9525)
			(end 0.4318 -0.9525)
			(stroke
				(width 0)
				(type default)
			)
			(fill no)
			(layer "F.CrtYd")
		)
		(fp_rect
			(start -0.4318 0.9525)
			(end 0.4318 -0.9525)
			(stroke
				(width 0)
				(type default)
			)
			(fill no)
			(layer "F.Fab")
		)
		(pad "1" smd custom
			(at 0 -0.4445 90)
			(size 0.1524 0.1524)
			(layers "F.Cu" "F.Mask" "F.Paste")
			(net "P12V_B")
			(options
				(clearance outline)
				(anchor circle)
			)
			(primitives
				(gr_poly
					(pts
						(arc
							(start 0.3048 -0.2032)
							(mid 0.275042 -0.275042)
							(end 0.2032 -0.3048)
						)
						(arc
							(start -0.2032 -0.3048)
							(mid -0.275042 -0.275042)
							(end -0.3048 -0.2032)
						)
						(arc
							(start -0.3048 0.2032)
							(mid -0.275042 0.275042)
							(end -0.2032 0.3048)
						)
						(arc
							(start 0.2032 0.3048)
							(mid 0.275042 0.275042)
							(end 0.3048 0.2032)
						)
					)
					(width 0)
					(fill yes)
				)
			)
		)
		(pad "2" smd custom
			(at 0 0.4445 90)
			(size 0.1524 0.1524)
			(layers "F.Cu" "F.Mask" "F.Paste")
			(net "SW_HDD_N13")
			(options
				(clearance outline)
				(anchor circle)
			)
			(primitives
				(gr_poly
					(pts
						(arc
							(start 0.3048 -0.2032)
							(mid 0.275042 -0.275042)
							(end 0.2032 -0.3048)
						)
						(arc
							(start -0.2032 -0.3048)
							(mid -0.275042 -0.275042)
							(end -0.3048 -0.2032)
						)
						(arc
							(start -0.3048 0.2032)
							(mid -0.275042 0.275042)
							(end -0.2032 0.3048)
						)
						(arc
							(start 0.2032 0.3048)
							(mid 0.275042 0.275042)
							(end 0.3048 0.2032)
						)
					)
					(width 0)
					(fill yes)
				)
			)
		)
	)
	(footprint ""
		(layer "F.Cu")
		(at 469.773 -35.56 -90)
		(property "Reference" "C489"
			(at 0 0 270)
			(layer "F.SilkS")
			(hide yes)
			(effects
				(font
					(size 1.27 1.27)
				)
			)
		)
		(property "Value" "SC4D7U25V5KX-1-GP"
			(at -0.0762 -6.1214 270)
			(unlocked yes)
			(layer "F.Fab")
			(hide yes)
			(effects
				(font
					(size 1.016 1.016)
					(thickness 0.1524)
				)
			)
		)
		(property "Device Type" "C805H58"
			(at -0.0762 -8.1534 270)
			(unlocked yes)
			(layer "F.Fab")
			(hide yes)
			(effects
				(font
					(size 1.016 1.016)
					(thickness 0.1524)
				)
			)
		)
		(duplicate_pad_numbers_are_jumpers no)
		(fp_line
			(start 0.635 0)
			(end -0.635 0)
			(stroke
				(width 0.508)
				(type default)
			)
			(layer "F.SilkS")
		)
		(fp_rect
			(start -0.9652 1.778)
			(end 0.9652 -1.778)
			(stroke
				(width 0)
				(type default)
			)
			(fill no)
			(layer "F.CrtYd")
		)
		(fp_poly
			(pts
				(xy -0.9652 -1.778) (xy 0.9652 -1.778) (xy 0.9652 1.778) (xy -0.9652 1.778)
			)
			(stroke
				(width 0)
				(type default)
			)
			(fill no)
			(layer "F.Fab")
		)
		(pad "1" smd rect
			(at 0 -0.9652 270)
			(size 1.397 1.143)
			(layers "F.Cu" "F.Mask" "F.Paste")
			(net "P12V_HDD35")
		)
		(pad "2" smd rect
			(at 0 0.9652 270)
			(size 1.397 1.143)
			(layers "F.Cu" "F.Mask" "F.Paste")
			(net "GND")
		)
	)
	(footprint ""
		(layer "F.Cu")
		(at 225.552 -303.6824 180)
		(property "Reference" "R505"
			(at 0 0 180)
			(layer "F.SilkS")
			(hide yes)
			(effects
				(font
					(size 1.27 1.27)
				)
			)
		)
		(property "Value" "10KR2F-2-GP"
			(at 0.064008 -3.993896 180)
			(unlocked yes)
			(layer "F.Fab")
			(hide yes)
			(effects
				(font
					(size 1.016 1.016)
					(thickness 0.1524)
				)
			)
		)
		(property "Device Type" "R402H16"
			(at 0.064008 -5.517896 180)
			(unlocked yes)
			(layer "F.Fab")
			(hide yes)
			(effects
				(font
					(size 1.016 1.016)
					(thickness 0.1524)
				)
			)
		)
		(duplicate_pad_numbers_are_jumpers no)
		(fp_line
			(start 0.508 -0.9398)
			(end -0.508 -0.9398)
			(stroke
				(width 0.1524)
				(type default)
			)
			(layer "F.SilkS")
		)
		(fp_line
			(start -0.508 -0.9398)
			(end -0.508 0.9398)
			(stroke
				(width 0.1524)
				(type default)
			)
			(layer "F.SilkS")
		)
		(fp_rect
			(start -0.508 0.9398)
			(end 0.508 -0.9398)
			(stroke
				(width 0)
				(type default)
			)
			(fill no)
			(layer "F.CrtYd")
		)
		(fp_rect
			(start -0.508 0.9398)
			(end 0.508 -0.9398)
			(stroke
				(width 0)
				(type default)
			)
			(fill no)
			(layer "F.Fab")
		)
		(pad "1" smd custom
			(at 0 -0.4445 180)
			(size 0.1397 0.1397)
			(layers "F.Cu" "F.Mask" "F.Paste")
			(net "P3V3_IN")
			(options
				(clearance outline)
				(anchor circle)
			)
			(primitives
				(gr_poly
					(pts
						(arc
							(start -0.1778 -0.2794)
							(mid -0.249642 -0.249642)
							(end -0.2794 -0.1778)
						)
						(arc
							(start -0.2794 0.1778)
							(mid -0.249642 0.249642)
							(end -0.1778 0.2794)
						)
						(arc
							(start 0.1778 0.2794)
							(mid 0.249642 0.249642)
							(end 0.2794 0.1778)
						)
						(arc
							(start 0.2794 -0.1778)
							(mid 0.249642 -0.249642)
							(end 0.1778 -0.2794)
						)
					)
					(width 0)
					(fill yes)
				)
			)
		)
		(pad "2" smd custom
			(at 0 0.4445 180)
			(size 0.1397 0.1397)
			(layers "F.Cu" "F.Mask" "F.Paste")
			(net "FANTACH_A_OE_N")
			(options
				(clearance outline)
				(anchor circle)
			)
			(primitives
				(gr_poly
					(pts
						(arc
							(start -0.1778 -0.2794)
							(mid -0.249642 -0.249642)
							(end -0.2794 -0.1778)
						)
						(arc
							(start -0.2794 0.1778)
							(mid -0.249642 0.249642)
							(end -0.1778 0.2794)
						)
						(arc
							(start 0.1778 0.2794)
							(mid 0.249642 0.249642)
							(end 0.2794 0.1778)
						)
						(arc
							(start 0.2794 -0.1778)
							(mid 0.249642 -0.249642)
							(end 0.1778 -0.2794)
						)
					)
					(width 0)
					(fill yes)
				)
			)
		)
	)
	(footprint ""
		(layer "F.Cu")
		(at 174.117 -99.314)
		(property "Reference" "R426"
			(at 0 0 0)
			(layer "F.SilkS")
			(hide yes)
			(effects
				(font
					(size 1.27 1.27)
				)
			)
		)
		(property "Value" "91R3F-1-GP"
			(at -0.0254 -2.5146 0)
			(unlocked yes)
			(layer "F.Fab")
			(hide yes)
			(effects
				(font
					(size 1.016 1.016)
					(thickness 0.1524)
				)
			)
		)
		(property "Device Type" "R603H22"
			(at -0.0254 -4.0386 0)
			(unlocked yes)
			(layer "F.Fab")
			(hide yes)
			(effects
				(font
					(size 1.016 1.016)
					(thickness 0.1524)
				)
			)
		)
		(duplicate_pad_numbers_are_jumpers no)
		(fp_line
			(start -0.4826 0)
			(end -0.2032 0)
			(stroke
				(width 0.2032)
				(type default)
			)
			(layer "F.SilkS")
		)
		(fp_line
			(start 0.2032 0)
			(end 0.4826 0)
			(stroke
				(width 0.2032)
				(type default)
			)
			(layer "F.SilkS")
		)
		(fp_rect
			(start -0.5842 1.3335)
			(end 0.5842 -1.3335)
			(stroke
				(width 0)
				(type default)
			)
			(fill no)
			(layer "F.CrtYd")
		)
		(fp_rect
			(start -0.5842 1.3335)
			(end 0.5842 -1.3335)
			(stroke
				(width 0)
				(type default)
			)
			(fill no)
			(layer "F.Fab")
		)
		(pad "1" smd custom
			(at 0 -0.762)
			(size 0.2159 0.2159)
			(layers "F.Cu" "F.Mask" "F.Paste")
			(net "P5V_B_2")
			(options
				(clearance outline)
				(anchor circle)
			)
			(primitives
				(gr_poly
					(pts
						(arc
							(start -0.3302 -0.4318)
							(mid -0.402042 -0.402042)
							(end -0.4318 -0.3302)
						)
						(arc
							(start -0.4318 0.3302)
							(mid -0.402042 0.402042)
							(end -0.3302 0.4318)
						)
						(arc
							(start 0.3302 0.4318)
							(mid 0.402042 0.402042)
							(end 0.4318 0.3302)
						)
						(arc
							(start 0.4318 -0.3302)
							(mid 0.402042 -0.402042)
							(end 0.3302 -0.4318)
						)
					)
					(width 0)
					(fill yes)
				)
			)
		)
		(pad "2" smd custom
			(at 0 0.762)
			(size 0.2159 0.2159)
			(layers "F.Cu" "F.Mask" "F.Paste")
			(net "DRV_ACT_17")
			(options
				(clearance outline)
				(anchor circle)
			)
			(primitives
				(gr_poly
					(pts
						(arc
							(start -0.3302 -0.4318)
							(mid -0.402042 -0.402042)
							(end -0.4318 -0.3302)
						)
						(arc
							(start -0.4318 0.3302)
							(mid -0.402042 0.402042)
							(end -0.3302 0.4318)
						)
						(arc
							(start 0.3302 0.4318)
							(mid 0.402042 0.402042)
							(end 0.4318 0.3302)
						)
						(arc
							(start 0.4318 -0.3302)
							(mid 0.402042 -0.402042)
							(end 0.3302 -0.4318)
						)
					)
					(width 0)
					(fill yes)
				)
			)
		)
	)
	(footprint ""
		(layer "F.Cu")
		(at 464.6168 -6.3754 -90)
		(property "Reference" "R140"
			(at 0 0 270)
			(layer "F.SilkS")
			(hide yes)
			(effects
				(font
					(size 1.27 1.27)
				)
			)
		)
		(property "Value" "4K7R2F-GP"
			(at 0.064008 -3.993896 270)
			(unlocked yes)
			(layer "F.Fab")
			(hide yes)
			(effects
				(font
					(size 1.016 1.016)
					(thickness 0.1524)
				)
			)
		)
		(property "Device Type" "R402H16"
			(at 0.064008 -5.517896 270)
			(unlocked yes)
			(layer "F.Fab")
			(hide yes)
			(effects
				(font
					(size 1.016 1.016)
					(thickness 0.1524)
				)
			)
		)
		(duplicate_pad_numbers_are_jumpers no)
		(fp_line
			(start -0.508 -0.9398)
			(end -0.508 0.9398)
			(stroke
				(width 0.1524)
				(type default)
			)
			(layer "F.SilkS")
		)
		(fp_line
			(start 0.508 -0.9398)
			(end -0.508 -0.9398)
			(stroke
				(width 0.1524)
				(type default)
			)
			(layer "F.SilkS")
		)
		(fp_rect
			(start -0.508 0.9398)
			(end 0.508 -0.9398)
			(stroke
				(width 0)
				(type default)
			)
			(fill no)
			(layer "F.CrtYd")
		)
		(fp_rect
			(start -0.508 0.9398)
			(end 0.508 -0.9398)
			(stroke
				(width 0)
				(type default)
			)
			(fill no)
			(layer "F.Fab")
		)
		(pad "1" smd custom
			(at 0 -0.4445 270)
			(size 0.1397 0.1397)
			(layers "F.Cu" "F.Mask" "F.Paste")
			(net "TEMP2_A1")
			(options
				(clearance outline)
				(anchor circle)
			)
			(primitives
				(gr_poly
					(pts
						(arc
							(start -0.1778 -0.2794)
							(mid -0.249642 -0.249642)
							(end -0.2794 -0.1778)
						)
						(arc
							(start -0.2794 0.1778)
							(mid -0.249642 0.249642)
							(end -0.1778 0.2794)
						)
						(arc
							(start 0.1778 0.2794)
							(mid 0.249642 0.249642)
							(end 0.2794 0.1778)
						)
						(arc
							(start 0.2794 -0.1778)
							(mid 0.249642 -0.249642)
							(end 0.1778 -0.2794)
						)
					)
					(width 0)
					(fill yes)
				)
			)
		)
		(pad "2" smd custom
			(at 0 0.4445 270)
			(size 0.1397 0.1397)
			(layers "F.Cu" "F.Mask" "F.Paste")
			(net "GND")
			(options
				(clearance outline)
				(anchor circle)
			)
			(primitives
				(gr_poly
					(pts
						(arc
							(start -0.1778 -0.2794)
							(mid -0.249642 -0.249642)
							(end -0.2794 -0.1778)
						)
						(arc
							(start -0.2794 0.1778)
							(mid -0.249642 0.249642)
							(end -0.1778 0.2794)
						)
						(arc
							(start 0.1778 0.2794)
							(mid 0.249642 0.249642)
							(end 0.2794 0.1778)
						)
						(arc
							(start 0.2794 -0.1778)
							(mid 0.249642 -0.249642)
							(end 0.1778 -0.2794)
						)
					)
					(width 0)
					(fill yes)
				)
			)
		)
	)
	(footprint ""
		(layer "F.Cu")
		(at 43.999912 -13.999972)
		(property "Reference" ""
			(at 0 0 0)
			(layer "F.SilkS")
			(hide yes)
			(effects
				(font
					(size 1.27 1.27)
				)
			)
		)
		(property "Value" "*"
			(at -6.3373 -0.4572 0)
			(unlocked yes)
			(layer "F.Fab")
			(hide yes)
			(effects
				(font
					(size 1.016 1.016)
					(thickness 0.1524)
				)
			)
		)
		(duplicate_pad_numbers_are_jumpers no)
		(fp_poly
			(pts
				(arc
					(start 5.0673 0)
					(mid -5.0673 0)
					(end 5.0673 0)
				)
			)
			(stroke
				(width 0)
				(type default)
			)
			(fill no)
			(layer "B.CrtYd")
		)
		(fp_poly
			(pts
				(arc
					(start 5.0673 0)
					(mid -5.0673 0)
					(end 5.0673 0)
				)
			)
			(stroke
				(width 0)
				(type default)
			)
			(fill no)
			(layer "F.CrtYd")
		)
		(fp_poly
			(pts
				(arc
					(start 5.0673 0)
					(mid -5.0673 0)
					(end 5.0673 0)
				)
			)
			(stroke
				(width 0)
				(type default)
			)
			(fill no)
			(layer "B.Fab")
		)
		(fp_poly
			(pts
				(arc
					(start 5.0673 0)
					(mid -5.0673 0)
					(end 5.0673 0)
				)
			)
			(stroke
				(width 0)
				(type default)
			)
			(fill no)
			(layer "F.Fab")
		)
		(pad "1" thru_hole circle
			(at 0 0)
			(size 9.525 9.525)
			(drill 3.556)
			(layers "*.Cu" "*.Mask")
			(remove_unused_layers no)
			(net "Net_37")
			(clearance -2.4765)
			(thermal_gap 0.3048)
			(padstack
				(mode front_inner_back)
				(layer "Inner"
					(shape circle)
					(size 3.9624 3.9624)
					(clearance 0.3048)
				)
				(layer "B.Cu"
					(shape circle)
					(size 9.525 9.525)
					(clearance -2.4765)
				)
			)
		)
		(zone
			(layers "F.Cu" "B.Cu" "In1.Cu" "In2.Cu" "In3.Cu" "In4.Cu" "In5.Cu" "In6.Cu")
			(hatch none 0.5)
			(connect_pads
				(clearance 0)
			)
			(min_thickness 0.25)
			(keepout
				(tracks not_allowed)
				(vias allowed)
				(pads allowed)
				(copperpour not_allowed)
				(footprints allowed)
			)
			(placement
				(enabled no)
				(sheetname "")
			)
			(fill
				(thermal_gap 0.5)
				(thermal_bridge_width 0.5)
				(island_removal_mode 0)
			)
			(polygon
				(pts
					(arc
						(start 48.762412 -13.999972)
						(mid 39.237412 -13.999972)
						(end 48.762412 -13.999972)
					)
				)
			)
		)
	)
	(footprint ""
		(layer "F.Cu")
		(at 190.0936 -35.5854 180)
		(property "Reference" "R741"
			(at 0 0 180)
			(layer "F.SilkS")
			(hide yes)
			(effects
				(font
					(size 1.27 1.27)
				)
			)
		)
		(property "Value" "220R3F-1-GP"
			(at -0.0254 -2.5146 180)
			(unlocked yes)
			(layer "F.Fab")
			(hide yes)
			(effects
				(font
					(size 1.016 1.016)
					(thickness 0.1524)
				)
			)
		)
		(property "Device Type" "R603H22"
			(at -0.0254 -4.0386 180)
			(unlocked yes)
			(layer "F.Fab")
			(hide yes)
			(effects
				(font
					(size 1.016 1.016)
					(thickness 0.1524)
				)
			)
		)
		(duplicate_pad_numbers_are_jumpers no)
		(fp_line
			(start 0.2032 0)
			(end 0.4826 0)
			(stroke
				(width 0.2032)
				(type default)
			)
			(layer "F.SilkS")
		)
		(fp_line
			(start -0.4826 0)
			(end -0.2032 0)
			(stroke
				(width 0.2032)
				(type default)
			)
			(layer "F.SilkS")
		)
		(fp_rect
			(start -0.5842 1.3335)
			(end 0.5842 -1.3335)
			(stroke
				(width 0)
				(type default)
			)
			(fill no)
			(layer "F.CrtYd")
		)
		(fp_rect
			(start -0.5842 1.3335)
			(end 0.5842 -1.3335)
			(stroke
				(width 0)
				(type default)
			)
			(fill no)
			(layer "F.Fab")
		)
		(pad "1" smd custom
			(at 0 -0.762 180)
			(size 0.2159 0.2159)
			(layers "F.Cu" "F.Mask" "F.Paste")
			(net "HDD_PRSNT_29")
			(options
				(clearance outline)
				(anchor circle)
			)
			(primitives
				(gr_poly
					(pts
						(arc
							(start -0.3302 -0.4318)
							(mid -0.402042 -0.402042)
							(end -0.4318 -0.3302)
						)
						(arc
							(start -0.4318 0.3302)
							(mid -0.402042 0.402042)
							(end -0.3302 0.4318)
						)
						(arc
							(start 0.3302 0.4318)
							(mid 0.402042 0.402042)
							(end 0.4318 0.3302)
						)
						(arc
							(start 0.4318 -0.3302)
							(mid 0.402042 -0.402042)
							(end 0.3302 -0.4318)
						)
					)
					(width 0)
					(fill yes)
				)
			)
		)
		(pad "2" smd custom
			(at 0 0.762 180)
			(size 0.2159 0.2159)
			(layers "F.Cu" "F.Mask" "F.Paste")
			(net "DRIVE_B_29_INS")
			(options
				(clearance outline)
				(anchor circle)
			)
			(primitives
				(gr_poly
					(pts
						(arc
							(start -0.3302 -0.4318)
							(mid -0.402042 -0.402042)
							(end -0.4318 -0.3302)
						)
						(arc
							(start -0.4318 0.3302)
							(mid -0.402042 0.402042)
							(end -0.3302 0.4318)
						)
						(arc
							(start 0.3302 0.4318)
							(mid 0.402042 0.402042)
							(end 0.4318 0.3302)
						)
						(arc
							(start 0.4318 -0.3302)
							(mid 0.402042 -0.402042)
							(end 0.3302 -0.4318)
						)
					)
					(width 0)
					(fill yes)
				)
			)
		)
	)
)
